(kicad_pcb
	(version 20260206)
	(generator "pcbnew")
	(generator_version "10.0")
	(general
		(thickness 1.6)
		(legacy_teardrops no)
	)
	(paper "A4")
	(title_block
		(title "Wiwynn_Tioga_Pass_MB.brd")
		(comment 1 "Tioga Pass / footprint 320 of 4770 (J1B1), pads 124-243 of 291")
	)
	(layers
		(0 "F.Cu" signal "TOP")
		(4 "In1.Cu" signal "L2GND")
		(6 "In2.Cu" signal "L3")
		(8 "In3.Cu" signal "L4GND")
		(10 "In4.Cu" signal "L5")
		(12 "In5.Cu" signal "L6GND")
		(14 "In6.Cu" signal "L7VCC")
		(16 "In7.Cu" signal "L8VCC")
		(18 "In8.Cu" signal "L9GND")
		(20 "In9.Cu" signal "L10")
		(22 "In10.Cu" signal "L11GND")
		(24 "In11.Cu" signal "L12")
		(26 "In12.Cu" signal "L13GND")
		(2 "B.Cu" signal "BOTTOM")
		(9 "F.Adhes" user "F.Adhesive")
		(11 "B.Adhes" user "B.Adhesive")
		(13 "F.Paste" user "Package Geometry/Pastemask Top")
		(15 "B.Paste" user "Package Geometry/Pastemask Bottom")
		(5 "F.SilkS" user "Ref Des/Silkscreen Top")
		(7 "B.SilkS" user "Ref Des/Silkscreen Bottom")
		(1 "F.Mask" user "Board Geometry/Soldermask Top")
		(3 "B.Mask" user "Board Geometry/Soldermask Bottom")
		(17 "Dwgs.User" user "User.Drawings")
		(19 "Cmts.User" user "User.Comments")
		(21 "Eco1.User" user "User.Eco1")
		(23 "Eco2.User" user "User.Eco2")
		(25 "Edge.Cuts" user "Board Geometry/Outline")
		(27 "Margin" user)
		(31 "F.CrtYd" user "Package Geometry/Place Bound Top")
		(29 "B.CrtYd" user "Package Geometry/Place Bound Bottom")
		(35 "F.Fab" user "Ref Des/Assembly Top")
		(33 "B.Fab" user "Ref Des/Assembly Bottom")
	)
	(footprint ""
		(layer "F.Cu")
		(at 29.699458 -133.0706 90)
		(property "Reference" "J1B1"
			(at -4.960112 38.372542 0)
			(unlocked yes)
			(layer "F.SilkS")
			(effects
				(font
					(size 0.7874 0.5842)
					(thickness 0.1524)
				)
				(justify left)
			)
		)
		(property "Value" ""
			(at 0 0 90)
			(layer "F.Fab")
			(effects
				(font
					(size 1.27 1.27)
				)
			)
		)
		(duplicate_pad_numbers_are_jumpers no)
		(pad "121" smd rect
			(at 0 107.100116 90)
			(size 1.8034 0.508)
			(layers "F.Cu" "F.Mask" "F.Paste")
			(net "M_K_DQS_DP<15>")
		)
		(pad "122" smd rect
			(at 0 107.95 90)
			(size 1.8034 0.508)
			(layers "F.Cu" "F.Mask" "F.Paste")
			(net "M_K_DQS_DN<15>")
		)
		(pad "123" smd rect
			(at 0 108.799884 90)
			(size 1.8034 0.508)
			(layers "F.Cu" "F.Mask" "F.Paste")
			(net "GND")
		)
		(pad "124" smd rect
			(at 0 109.650022 90)
			(size 1.8034 0.508)
			(layers "F.Cu" "F.Mask" "F.Paste")
			(net "M_K_DQ<55>")
		)
		(pad "125" smd rect
			(at 0 110.499906 90)
			(size 1.8034 0.508)
			(layers "F.Cu" "F.Mask" "F.Paste")
			(net "GND")
		)
		(pad "126" smd rect
			(at 0 111.350044 90)
			(size 1.8034 0.508)
			(layers "F.Cu" "F.Mask" "F.Paste")
			(net "M_K_DQ<51>")
		)
		(pad "127" smd rect
			(at 0 112.199928 90)
			(size 1.8034 0.508)
			(layers "F.Cu" "F.Mask" "F.Paste")
			(net "GND")
		)
		(pad "128" smd rect
			(at 0 113.050066 90)
			(size 1.8034 0.508)
			(layers "F.Cu" "F.Mask" "F.Paste")
			(net "M_K_DQ<61>")
		)
		(pad "129" smd rect
			(at 0 113.89995 90)
			(size 1.8034 0.508)
			(layers "F.Cu" "F.Mask" "F.Paste")
			(net "GND")
		)
		(pad "130" smd rect
			(at 0 114.750088 90)
			(size 1.8034 0.508)
			(layers "F.Cu" "F.Mask" "F.Paste")
			(net "M_K_DQ<57>")
		)
		(pad "131" smd rect
			(at 0 115.599972 90)
			(size 1.8034 0.508)
			(layers "F.Cu" "F.Mask" "F.Paste")
			(net "GND")
		)
		(pad "132" smd rect
			(at 0 116.45011 90)
			(size 1.8034 0.508)
			(layers "F.Cu" "F.Mask" "F.Paste")
			(net "M_K_DQS_DP<16>")
		)
		(pad "133" smd rect
			(at 0 117.299994 90)
			(size 1.8034 0.508)
			(layers "F.Cu" "F.Mask" "F.Paste")
			(net "M_K_DQS_DN<16>")
		)
		(pad "134" smd rect
			(at 0 118.149878 90)
			(size 1.8034 0.508)
			(layers "F.Cu" "F.Mask" "F.Paste")
			(net "GND")
		)
		(pad "135" smd rect
			(at 0 119.000016 90)
			(size 1.8034 0.508)
			(layers "F.Cu" "F.Mask" "F.Paste")
			(net "M_K_DQ<63>")
		)
		(pad "136" smd rect
			(at 0 119.8499 90)
			(size 1.8034 0.508)
			(layers "F.Cu" "F.Mask" "F.Paste")
			(net "GND")
		)
		(pad "137" smd rect
			(at 0 120.700038 90)
			(size 1.8034 0.508)
			(layers "F.Cu" "F.Mask" "F.Paste")
			(net "M_K_DQ<59>")
		)
		(pad "138" smd rect
			(at 0 121.549922 90)
			(size 1.8034 0.508)
			(layers "F.Cu" "F.Mask" "F.Paste")
			(net "GND")
		)
		(pad "139" smd rect
			(at 0 122.40006 90)
			(size 1.8034 0.508)
			(layers "F.Cu" "F.Mask" "F.Paste")
			(net "GND")
		)
		(pad "140" smd rect
			(at 0 123.249944 90)
			(size 1.8034 0.508)
			(layers "F.Cu" "F.Mask" "F.Paste")
			(net "GND")
		)
		(pad "141" smd rect
			(at 0 124.100082 90)
			(size 1.8034 0.508)
			(layers "F.Cu" "F.Mask" "F.Paste")
			(net "SMB_DDR_KLM_VPP_SCL")
		)
		(pad "142" smd rect
			(at 0 124.949966 90)
			(size 1.8034 0.508)
			(layers "F.Cu" "F.Mask" "F.Paste")
			(net "PVPP_KLM")
		)
		(pad "143" smd rect
			(at 0 125.800104 90)
			(size 1.8034 0.508)
			(layers "F.Cu" "F.Mask" "F.Paste")
			(net "PVPP_KLM")
		)
		(pad "144" smd rect
			(at 0 126.649988 90)
			(size 1.8034 0.508)
			(layers "F.Cu" "F.Mask" "F.Paste")
			(net "TP_CH_K_DIMM_K0_RFU_2")
		)
		(pad "145" smd rect
			(at 4.59994 0 90)
			(size 1.8034 0.508)
			(layers "F.Cu" "F.Mask" "F.Paste")
			(net "P12V_NVDIMM_KLM")
		)
		(pad "146" smd rect
			(at 4.59994 0.849884 90)
			(size 1.8034 0.508)
			(layers "F.Cu" "F.Mask" "F.Paste")
			(net "M_K_VREF")
		)
		(pad "147" smd rect
			(at 4.59994 1.700022 90)
			(size 1.8034 0.508)
			(layers "F.Cu" "F.Mask" "F.Paste")
			(net "GND")
		)
		(pad "148" smd rect
			(at 4.59994 2.549906 90)
			(size 1.8034 0.508)
			(layers "F.Cu" "F.Mask" "F.Paste")
			(net "M_K_DQ<4>")
		)
		(pad "149" smd rect
			(at 4.59994 3.400044 90)
			(size 1.8034 0.508)
			(layers "F.Cu" "F.Mask" "F.Paste")
			(net "GND")
		)
		(pad "150" smd rect
			(at 4.59994 4.249928 90)
			(size 1.8034 0.508)
			(layers "F.Cu" "F.Mask" "F.Paste")
			(net "M_K_DQ<0>")
		)
		(pad "151" smd rect
			(at 4.59994 5.100066 90)
			(size 1.8034 0.508)
			(layers "F.Cu" "F.Mask" "F.Paste")
			(net "GND")
		)
		(pad "152" smd rect
			(at 4.59994 5.94995 90)
			(size 1.8034 0.508)
			(layers "F.Cu" "F.Mask" "F.Paste")
			(net "M_K_DQS_DN<0>")
		)
		(pad "153" smd rect
			(at 4.59994 6.800088 90)
			(size 1.8034 0.508)
			(layers "F.Cu" "F.Mask" "F.Paste")
			(net "M_K_DQS_DP<0>")
		)
		(pad "154" smd rect
			(at 4.59994 7.649972 90)
			(size 1.8034 0.508)
			(layers "F.Cu" "F.Mask" "F.Paste")
			(net "GND")
		)
		(pad "155" smd rect
			(at 4.59994 8.50011 90)
			(size 1.8034 0.508)
			(layers "F.Cu" "F.Mask" "F.Paste")
			(net "M_K_DQ<6>")
		)
		(pad "156" smd rect
			(at 4.59994 9.349994 90)
			(size 1.8034 0.508)
			(layers "F.Cu" "F.Mask" "F.Paste")
			(net "GND")
		)
		(pad "157" smd rect
			(at 4.59994 10.199878 90)
			(size 1.8034 0.508)
			(layers "F.Cu" "F.Mask" "F.Paste")
			(net "M_K_DQ<2>")
		)
		(pad "158" smd rect
			(at 4.59994 11.050016 90)
			(size 1.8034 0.508)
			(layers "F.Cu" "F.Mask" "F.Paste")
			(net "GND")
		)
		(pad "159" smd rect
			(at 4.59994 11.8999 90)
			(size 1.8034 0.508)
			(layers "F.Cu" "F.Mask" "F.Paste")
			(net "M_K_DQ<12>")
		)
		(pad "160" smd rect
			(at 4.59994 12.750038 90)
			(size 1.8034 0.508)
			(layers "F.Cu" "F.Mask" "F.Paste")
			(net "GND")
		)
		(pad "161" smd rect
			(at 4.59994 13.599922 90)
			(size 1.8034 0.508)
			(layers "F.Cu" "F.Mask" "F.Paste")
			(net "M_K_DQ<8>")
		)
		(pad "162" smd rect
			(at 4.59994 14.45006 90)
			(size 1.8034 0.508)
			(layers "F.Cu" "F.Mask" "F.Paste")
			(net "GND")
		)
		(pad "163" smd rect
			(at 4.59994 15.299944 90)
			(size 1.8034 0.508)
			(layers "F.Cu" "F.Mask" "F.Paste")
			(net "M_K_DQS_DN<1>")
		)
		(pad "164" smd rect
			(at 4.59994 16.150082 90)
			(size 1.8034 0.508)
			(layers "F.Cu" "F.Mask" "F.Paste")
			(net "M_K_DQS_DP<1>")
		)
		(pad "165" smd rect
			(at 4.59994 16.999966 90)
			(size 1.8034 0.508)
			(layers "F.Cu" "F.Mask" "F.Paste")
			(net "GND")
		)
		(pad "166" smd rect
			(at 4.59994 17.850104 90)
			(size 1.8034 0.508)
			(layers "F.Cu" "F.Mask" "F.Paste")
			(net "M_K_DQ<14>")
		)
		(pad "167" smd rect
			(at 4.59994 18.699988 90)
			(size 1.8034 0.508)
			(layers "F.Cu" "F.Mask" "F.Paste")
			(net "GND")
		)
		(pad "168" smd rect
			(at 4.59994 19.550126 90)
			(size 1.8034 0.508)
			(layers "F.Cu" "F.Mask" "F.Paste")
			(net "M_K_DQ<10>")
		)
		(pad "169" smd rect
			(at 4.59994 20.40001 90)
			(size 1.8034 0.508)
			(layers "F.Cu" "F.Mask" "F.Paste")
			(net "GND")
		)
		(pad "170" smd rect
			(at 4.59994 21.249894 90)
			(size 1.8034 0.508)
			(layers "F.Cu" "F.Mask" "F.Paste")
			(net "M_K_DQ<20>")
		)
		(pad "171" smd rect
			(at 4.59994 22.100032 90)
			(size 1.8034 0.508)
			(layers "F.Cu" "F.Mask" "F.Paste")
			(net "GND")
		)
		(pad "172" smd rect
			(at 4.59994 22.949916 90)
			(size 1.8034 0.508)
			(layers "F.Cu" "F.Mask" "F.Paste")
			(net "M_K_DQ<16>")
		)
		(pad "173" smd rect
			(at 4.59994 23.800054 90)
			(size 1.8034 0.508)
			(layers "F.Cu" "F.Mask" "F.Paste")
			(net "GND")
		)
		(pad "174" smd rect
			(at 4.59994 24.649938 90)
			(size 1.8034 0.508)
			(layers "F.Cu" "F.Mask" "F.Paste")
			(net "M_K_DQS_DN<2>")
		)
		(pad "175" smd rect
			(at 4.59994 25.500076 90)
			(size 1.8034 0.508)
			(layers "F.Cu" "F.Mask" "F.Paste")
			(net "M_K_DQS_DP<2>")
		)
		(pad "176" smd rect
			(at 4.59994 26.34996 90)
			(size 1.8034 0.508)
			(layers "F.Cu" "F.Mask" "F.Paste")
			(net "GND")
		)
		(pad "177" smd rect
			(at 4.59994 27.200098 90)
			(size 1.8034 0.508)
			(layers "F.Cu" "F.Mask" "F.Paste")
			(net "M_K_DQ<22>")
		)
		(pad "178" smd rect
			(at 4.59994 28.049982 90)
			(size 1.8034 0.508)
			(layers "F.Cu" "F.Mask" "F.Paste")
			(net "GND")
		)
		(pad "179" smd rect
			(at 4.59994 28.90012 90)
			(size 1.8034 0.508)
			(layers "F.Cu" "F.Mask" "F.Paste")
			(net "M_K_DQ<18>")
		)
		(pad "180" smd rect
			(at 4.59994 29.750004 90)
			(size 1.8034 0.508)
			(layers "F.Cu" "F.Mask" "F.Paste")
			(net "GND")
		)
		(pad "181" smd rect
			(at 4.59994 30.599888 90)
			(size 1.8034 0.508)
			(layers "F.Cu" "F.Mask" "F.Paste")
			(net "M_K_DQ<28>")
		)
		(pad "182" smd rect
			(at 4.59994 31.450026 90)
			(size 1.8034 0.508)
			(layers "F.Cu" "F.Mask" "F.Paste")
			(net "GND")
		)
		(pad "183" smd rect
			(at 4.59994 32.29991 90)
			(size 1.8034 0.508)
			(layers "F.Cu" "F.Mask" "F.Paste")
			(net "M_K_DQ<24>")
		)
		(pad "184" smd rect
			(at 4.59994 33.150048 90)
			(size 1.8034 0.508)
			(layers "F.Cu" "F.Mask" "F.Paste")
			(net "GND")
		)
		(pad "185" smd rect
			(at 4.59994 33.999932 90)
			(size 1.8034 0.508)
			(layers "F.Cu" "F.Mask" "F.Paste")
			(net "M_K_DQS_DN<3>")
		)
		(pad "186" smd rect
			(at 4.59994 34.85007 90)
			(size 1.8034 0.508)
			(layers "F.Cu" "F.Mask" "F.Paste")
			(net "M_K_DQS_DP<3>")
		)
		(pad "187" smd rect
			(at 4.59994 35.699954 90)
			(size 1.8034 0.508)
			(layers "F.Cu" "F.Mask" "F.Paste")
			(net "GND")
		)
		(pad "188" smd rect
			(at 4.59994 36.550092 90)
			(size 1.8034 0.508)
			(layers "F.Cu" "F.Mask" "F.Paste")
			(net "M_K_DQ<30>")
		)
		(pad "189" smd rect
			(at 4.59994 37.399976 90)
			(size 1.8034 0.508)
			(layers "F.Cu" "F.Mask" "F.Paste")
			(net "GND")
		)
		(pad "190" smd rect
			(at 4.59994 38.250114 90)
			(size 1.8034 0.508)
			(layers "F.Cu" "F.Mask" "F.Paste")
			(net "M_K_DQ<26>")
		)
		(pad "191" smd rect
			(at 4.59994 39.099998 90)
			(size 1.8034 0.508)
			(layers "F.Cu" "F.Mask" "F.Paste")
			(net "GND")
		)
		(pad "192" smd rect
			(at 4.59994 39.949882 90)
			(size 1.8034 0.508)
			(layers "F.Cu" "F.Mask" "F.Paste")
			(net "M_K_ECC<4>")
		)
		(pad "193" smd rect
			(at 4.59994 40.80002 90)
			(size 1.8034 0.508)
			(layers "F.Cu" "F.Mask" "F.Paste")
			(net "GND")
		)
		(pad "194" smd rect
			(at 4.59994 41.649904 90)
			(size 1.8034 0.508)
			(layers "F.Cu" "F.Mask" "F.Paste")
			(net "M_K_ECC<0>")
		)
		(pad "195" smd rect
			(at 4.59994 42.500042 90)
			(size 1.8034 0.508)
			(layers "F.Cu" "F.Mask" "F.Paste")
			(net "GND")
		)
		(pad "196" smd rect
			(at 4.59994 43.349926 90)
			(size 1.8034 0.508)
			(layers "F.Cu" "F.Mask" "F.Paste")
			(net "M_K_DQS_DN<8>")
		)
		(pad "197" smd rect
			(at 4.59994 44.200064 90)
			(size 1.8034 0.508)
			(layers "F.Cu" "F.Mask" "F.Paste")
			(net "M_K_DQS_DP<8>")
		)
		(pad "198" smd rect
			(at 4.59994 45.049948 90)
			(size 1.8034 0.508)
			(layers "F.Cu" "F.Mask" "F.Paste")
			(net "GND")
		)
		(pad "199" smd rect
			(at 4.59994 45.900086 90)
			(size 1.8034 0.508)
			(layers "F.Cu" "F.Mask" "F.Paste")
			(net "M_K_ECC<6>")
		)
		(pad "200" smd rect
			(at 4.59994 46.74997 90)
			(size 1.8034 0.508)
			(layers "F.Cu" "F.Mask" "F.Paste")
			(net "GND")
		)
		(pad "201" smd rect
			(at 4.59994 47.600108 90)
			(size 1.8034 0.508)
			(layers "F.Cu" "F.Mask" "F.Paste")
			(net "M_K_ECC<2>")
		)
		(pad "202" smd rect
			(at 4.59994 48.449992 90)
			(size 1.8034 0.508)
			(layers "F.Cu" "F.Mask" "F.Paste")
			(net "GND")
		)
		(pad "203" smd rect
			(at 4.59994 49.299876 90)
			(size 1.8034 0.508)
			(layers "F.Cu" "F.Mask" "F.Paste")
			(net "M_K_CKE<1>")
		)
		(pad "204" smd rect
			(at 4.59994 50.150014 90)
			(size 1.8034 0.508)
			(layers "F.Cu" "F.Mask" "F.Paste")
			(net "PVDDQ_KLM")
		)
		(pad "205" smd rect
			(at 4.59994 50.999898 90)
			(size 1.8034 0.508)
			(layers "F.Cu" "F.Mask" "F.Paste")
			(net "TP_CH_K_DIMM_K0_RFU_0")
		)
		(pad "206" smd rect
			(at 4.59994 51.850036 90)
			(size 1.8034 0.508)
			(layers "F.Cu" "F.Mask" "F.Paste")
			(net "PVDDQ_KLM")
		)
		(pad "207" smd rect
			(at 4.59994 52.69992 90)
			(size 1.8034 0.508)
			(layers "F.Cu" "F.Mask" "F.Paste")
			(net "M_K_BG<1>")
		)
		(pad "208" smd rect
			(at 4.59994 53.550058 90)
			(size 1.8034 0.508)
			(layers "F.Cu" "F.Mask" "F.Paste")
			(net "M_K_ALERT_N")
		)
		(pad "209" smd rect
			(at 4.59994 54.399942 90)
			(size 1.8034 0.508)
			(layers "F.Cu" "F.Mask" "F.Paste")
			(net "PVDDQ_KLM")
		)
		(pad "210" smd rect
			(at 4.59994 55.25008 90)
			(size 1.8034 0.508)
			(layers "F.Cu" "F.Mask" "F.Paste")
			(net "M_K_MA<11>")
		)
		(pad "211" smd rect
			(at 4.59994 56.099964 90)
			(size 1.8034 0.508)
			(layers "F.Cu" "F.Mask" "F.Paste")
			(net "M_K_MA<7>")
		)
		(pad "212" smd rect
			(at 4.59994 56.950102 90)
			(size 1.8034 0.508)
			(layers "F.Cu" "F.Mask" "F.Paste")
			(net "PVDDQ_KLM")
		)
		(pad "213" smd rect
			(at 4.59994 57.799986 90)
			(size 1.8034 0.508)
			(layers "F.Cu" "F.Mask" "F.Paste")
			(net "M_K_MA<5>")
		)
		(pad "214" smd rect
			(at 4.59994 58.650124 90)
			(size 1.8034 0.508)
			(layers "F.Cu" "F.Mask" "F.Paste")
			(net "M_K_MA<4>")
		)
		(pad "215" smd rect
			(at 4.59994 59.500008 90)
			(size 1.8034 0.508)
			(layers "F.Cu" "F.Mask" "F.Paste")
			(net "PVDDQ_KLM")
		)
		(pad "216" smd rect
			(at 4.59994 60.349892 90)
			(size 1.8034 0.508)
			(layers "F.Cu" "F.Mask" "F.Paste")
			(net "M_K_MA<2>")
		)
		(pad "217" smd rect
			(at 4.59994 61.20003 90)
			(size 1.8034 0.508)
			(layers "F.Cu" "F.Mask" "F.Paste")
			(net "PVDDQ_KLM")
		)
		(pad "218" smd rect
			(at 4.59994 62.049914 90)
			(size 1.8034 0.508)
			(layers "F.Cu" "F.Mask" "F.Paste")
			(net "M_K_CLK_DP<1>")
		)
		(pad "219" smd rect
			(at 4.59994 62.900052 90)
			(size 1.8034 0.508)
			(layers "F.Cu" "F.Mask" "F.Paste")
			(net "M_K_CLK_DN<1>")
		)
		(pad "220" smd rect
			(at 4.59994 63.749936 90)
			(size 1.8034 0.508)
			(layers "F.Cu" "F.Mask" "F.Paste")
			(net "PVDDQ_KLM")
		)
		(pad "221" smd rect
			(at 4.59994 64.600074 90)
			(size 1.8034 0.508)
			(layers "F.Cu" "F.Mask" "F.Paste")
			(net "PVTT_KLM")
		)
		(pad "222" smd rect
			(at 4.59994 70.550024 90)
			(size 1.8034 0.508)
			(layers "F.Cu" "F.Mask" "F.Paste")
			(net "M_K_PAR")
		)
		(pad "223" smd rect
			(at 4.59994 71.399908 90)
			(size 1.8034 0.508)
			(layers "F.Cu" "F.Mask" "F.Paste")
			(net "PVDDQ_KLM")
		)
		(pad "224" smd rect
			(at 4.59994 72.250046 90)
			(size 1.8034 0.508)
			(layers "F.Cu" "F.Mask" "F.Paste")
			(net "M_K_BA<1>")
		)
		(pad "225" smd rect
			(at 4.59994 73.09993 90)
			(size 1.8034 0.508)
			(layers "F.Cu" "F.Mask" "F.Paste")
			(net "M_K_MA<10>")
		)
		(pad "226" smd rect
			(at 4.59994 73.950068 90)
			(size 1.8034 0.508)
			(layers "F.Cu" "F.Mask" "F.Paste")
			(net "PVDDQ_KLM")
		)
		(pad "227" smd rect
			(at 4.59994 74.799952 90)
			(size 1.8034 0.508)
			(layers "F.Cu" "F.Mask" "F.Paste")
			(net "TP_CH_K_DIMM_K0_RFU_1")
		)
		(pad "228" smd rect
			(at 4.59994 75.65009 90)
			(size 1.8034 0.508)
			(layers "F.Cu" "F.Mask" "F.Paste")
			(net "M_K_MA<14>")
		)
		(pad "229" smd rect
			(at 4.59994 76.499974 90)
			(size 1.8034 0.508)
			(layers "F.Cu" "F.Mask" "F.Paste")
			(net "PVDDQ_KLM")
		)
		(pad "230" smd rect
			(at 4.59994 77.350112 90)
			(size 1.8034 0.508)
			(layers "F.Cu" "F.Mask" "F.Paste")
			(net "FM_ADR_COMPLETE_KLM_N")
		)
		(pad "231" smd rect
			(at 4.59994 78.199996 90)
			(size 1.8034 0.508)
			(layers "F.Cu" "F.Mask" "F.Paste")
			(net "PVDDQ_KLM")
		)
		(pad "232" smd rect
			(at 4.59994 79.04988 90)
			(size 1.8034 0.508)
			(layers "F.Cu" "F.Mask" "F.Paste")
			(net "M_K_MA<13>")
		)
		(pad "233" smd rect
			(at 4.59994 79.900018 90)
			(size 1.8034 0.508)
			(layers "F.Cu" "F.Mask" "F.Paste")
			(net "PVDDQ_KLM")
		)
		(pad "234" smd rect
			(at 4.59994 80.749902 90)
			(size 1.8034 0.508)
			(layers "F.Cu" "F.Mask" "F.Paste")
			(net "M_K_MA<17>")
		)
		(pad "235" smd rect
			(at 4.59994 81.60004 90)
			(size 1.8034 0.508)
			(layers "F.Cu" "F.Mask" "F.Paste")
			(net "M_K_C<2>")
		)
		(pad "236" smd rect
			(at 4.59994 82.449924 90)
			(size 1.8034 0.508)
			(layers "F.Cu" "F.Mask" "F.Paste")
			(net "PVDDQ_KLM")
		)
		(pad "237" smd rect
			(at 4.59994 83.300062 90)
			(size 1.8034 0.508)
			(layers "F.Cu" "F.Mask" "F.Paste")
			(net "M_K_CS_N<3>")
		)
		(pad "238" smd rect
			(at 4.59994 84.149946 90)
			(size 1.8034 0.508)
			(layers "F.Cu" "F.Mask" "F.Paste")
			(net "GND")
		)
		(pad "239" smd rect
			(at 4.59994 85.000084 90)
			(size 1.8034 0.508)
			(layers "F.Cu" "F.Mask" "F.Paste")
			(net "GND")
		)
		(pad "240" smd rect
			(at 4.59994 85.849968 90)
			(size 1.8034 0.508)
			(layers "F.Cu" "F.Mask" "F.Paste")
			(net "M_K_DQ<36>")
		)
	)
)
